(kicad_pcb
	(version 20260206)
	(generator "pcbnew")
	(generator_version "10.0")
	(general
		(thickness 1.6)
		(legacy_teardrops no)
	)
	(paper "A4")
	(title_block
		(title "03242023_DA0F0TMBIJ0_F0T_Motherboard_J_brd_V01_OCP.brd")
		(comment 1 "Grand Teton / footprints 622-628 of 6105")
	)
	(layers
		(0 "F.Cu" signal "TOP")
		(4 "In1.Cu" signal "GND")
		(6 "In2.Cu" signal "IN1")
		(8 "In3.Cu" signal "GND1")
		(10 "In4.Cu" signal "IN2")
		(12 "In5.Cu" signal "GND2")
		(14 "In6.Cu" signal "IN3")
		(16 "In7.Cu" signal "GND3")
		(18 "In8.Cu" signal "VCC")
		(20 "In9.Cu" signal "VCC1")
		(22 "In10.Cu" signal "GND4")
		(24 "In11.Cu" signal "IN4")
		(26 "In12.Cu" signal "GND5")
		(28 "In13.Cu" signal "IN5")
		(30 "In14.Cu" signal "GND6")
		(32 "In15.Cu" signal "IN6")
		(34 "In16.Cu" signal "GND7")
		(2 "B.Cu" signal "BOTTOM")
		(9 "F.Adhes" user "F.Adhesive")
		(11 "B.Adhes" user "B.Adhesive")
		(13 "F.Paste" user "Package Geometry/Pastemask Top")
		(15 "B.Paste" user "Package Geometry/Pastemask Bottom")
		(5 "F.SilkS" user "Ref Des/Silkscreen Top")
		(7 "B.SilkS" user "Ref Des/Silkscreen Bottom")
		(1 "F.Mask" user "Board Geometry/Soldermask Top")
		(3 "B.Mask" user "Board Geometry/Soldermask Bottom")
		(17 "Dwgs.User" user "User.Drawings")
		(19 "Cmts.User" user "User.Comments")
		(21 "Eco1.User" user "User.Eco1")
		(23 "Eco2.User" user "User.Eco2")
		(25 "Edge.Cuts" user "Board Geometry/Outline")
		(27 "Margin" user)
		(31 "F.CrtYd" user "Package Geometry/Place Bound Top")
		(29 "B.CrtYd" user "Package Geometry/Place Bound Bottom")
		(35 "F.Fab" user "Ref Des/Assembly Top")
		(33 "B.Fab" user "Ref Des/Assembly Bottom")
	)
	(footprint ""
		(layer "F.Cu")
		(at 324.9168 -34.178748 135)
		(property "Reference" "C1508"
			(at 0 0 135)
			(layer "F.SilkS")
			(hide yes)
			(effects
				(font
					(size 1.27 1.27)
				)
			)
		)
		(property "Value" ""
			(at 0 0 135)
			(layer "F.Fab")
			(effects
				(font
					(size 1.27 1.27)
				)
			)
		)
		(duplicate_pad_numbers_are_jumpers no)
		(fp_line
			(start 0.787389 -0.406267)
			(end 0.787389 0.406267)
			(stroke
				(width 0.1524)
				(type default)
			)
			(layer "F.SilkS")
		)
		(fp_line
			(start 0.787389 0.406267)
			(end -0.787389 0.406267)
			(stroke
				(width 0.1524)
				(type default)
			)
			(layer "F.SilkS")
		)
		(fp_line
			(start -0.787389 -0.406267)
			(end 0.787389 -0.406267)
			(stroke
				(width 0.1524)
				(type default)
			)
			(layer "F.SilkS")
		)
		(fp_line
			(start -0.787389 0.406267)
			(end -0.787389 -0.406267)
			(stroke
				(width 0.1524)
				(type default)
			)
			(layer "F.SilkS")
		)
		(fp_line
			(start 0.679446 -0.30479)
			(end 0.679446 0.30479)
			(stroke
				(width 0.1)
				(type default)
			)
			(layer "F.Fab")
		)
		(fp_line
			(start 0.120515 -0.30479)
			(end 0.679446 -0.30479)
			(stroke
				(width 0.1)
				(type default)
			)
			(layer "F.Fab")
		)
		(fp_line
			(start 0.120695 -0.279466)
			(end 0.120515 -0.30479)
			(stroke
				(width 0.1)
				(type default)
			)
			(layer "F.Fab")
		)
		(fp_line
			(start 0.679446 0.30479)
			(end 0.120515 0.30479)
			(stroke
				(width 0.1)
				(type default)
			)
			(layer "F.Fab")
		)
		(fp_line
			(start -0.120695 -0.304969)
			(end -0.120695 -0.279466)
			(stroke
				(width 0.1)
				(type default)
			)
			(layer "F.Fab")
		)
		(fp_line
			(start -0.120695 -0.279466)
			(end 0.120695 -0.279466)
			(stroke
				(width 0.1)
				(type default)
			)
			(layer "F.Fab")
		)
		(fp_line
			(start 0.120335 0.279466)
			(end -0.120695 0.279466)
			(stroke
				(width 0.1)
				(type default)
			)
			(layer "F.Fab")
		)
		(fp_line
			(start 0.120515 0.30479)
			(end 0.120335 0.279466)
			(stroke
				(width 0.1)
				(type default)
			)
			(layer "F.Fab")
		)
		(fp_line
			(start -0.679446 -0.305149)
			(end -0.120695 -0.304969)
			(stroke
				(width 0.1)
				(type default)
			)
			(layer "F.Fab")
		)
		(fp_line
			(start -0.120695 0.279466)
			(end -0.120515 0.30479)
			(stroke
				(width 0.1)
				(type default)
			)
			(layer "F.Fab")
		)
		(fp_line
			(start -0.120515 0.30479)
			(end -0.679446 0.30479)
			(stroke
				(width 0.1)
				(type default)
			)
			(layer "F.Fab")
		)
		(fp_line
			(start -0.679446 0.30479)
			(end -0.679446 -0.305149)
			(stroke
				(width 0.1)
				(type default)
			)
			(layer "F.Fab")
		)
		(pad "1" smd circle
			(at -0.40005 0 135)
			(size 0 0)
			(layers "F.Cu" "F.Mask" "F.Paste")
			(net "XTAL_PCH_RTC1")
		)
		(pad "2" smd circle
			(at 0.40005 0 135)
			(size 0 0)
			(layers "F.Cu" "F.Mask" "F.Paste")
			(net "GND")
		)
	)
	(footprint ""
		(layer "F.Cu")
		(at 329.806808 -408.517344 -90)
		(property "Reference" "C918"
			(at 0 0 270)
			(layer "F.SilkS")
			(hide yes)
			(effects
				(font
					(size 1.27 1.27)
				)
			)
		)
		(property "Value" ""
			(at 0 0 270)
			(layer "F.Fab")
			(effects
				(font
					(size 1.27 1.27)
				)
			)
		)
		(duplicate_pad_numbers_are_jumpers no)
		(fp_line
			(start -0.299974 0.150114)
			(end -0.299974 -0.150114)
			(stroke
				(width 0.1)
				(type default)
			)
			(layer "F.Fab")
		)
		(fp_line
			(start 0.299974 0.150114)
			(end -0.299974 0.150114)
			(stroke
				(width 0.1)
				(type default)
			)
			(layer "F.Fab")
		)
		(fp_line
			(start -0.299974 -0.150114)
			(end 0.299974 -0.150114)
			(stroke
				(width 0.1)
				(type default)
			)
			(layer "F.Fab")
		)
		(fp_line
			(start 0.299974 -0.150114)
			(end 0.299974 0.150114)
			(stroke
				(width 0.1)
				(type default)
			)
			(layer "F.Fab")
		)
		(pad "1" smd rect
			(at -0.2667 0 270)
			(size 0.3048 0.381)
			(layers "F.Cu" "F.Mask" "F.Paste")
			(net "P5E_CPU0_PE0_TX_C_DN<7>")
		)
		(pad "2" smd rect
			(at 0.2667 0 270)
			(size 0.3048 0.381)
			(layers "F.Cu" "F.Mask" "F.Paste")
			(net "P5E_CPU0_PE0_TX_DN<7>")
		)
	)
	(footprint ""
		(layer "F.Cu")
		(at 120.975374 -360.043222 90)
		(property "Reference" "PC2002"
			(at 0 0 90)
			(layer "F.SilkS")
			(hide yes)
			(effects
				(font
					(size 1.27 1.27)
				)
			)
		)
		(property "Value" ""
			(at 0 0 90)
			(layer "F.Fab")
			(effects
				(font
					(size 1.27 1.27)
				)
			)
		)
		(duplicate_pad_numbers_are_jumpers no)
		(fp_line
			(start 0.7874 -0.4064)
			(end 0.7874 0.4064)
			(stroke
				(width 0.1524)
				(type default)
			)
			(layer "F.SilkS")
		)
		(fp_line
			(start -0.7874 -0.4064)
			(end 0.7874 -0.4064)
			(stroke
				(width 0.1524)
				(type default)
			)
			(layer "F.SilkS")
		)
		(fp_line
			(start 0.7874 0.4064)
			(end -0.7874 0.4064)
			(stroke
				(width 0.1524)
				(type default)
			)
			(layer "F.SilkS")
		)
		(fp_line
			(start -0.7874 0.4064)
			(end -0.7874 -0.4064)
			(stroke
				(width 0.1524)
				(type default)
			)
			(layer "F.SilkS")
		)
		(fp_line
			(start -0.12065 -0.305054)
			(end -0.12065 -0.2794)
			(stroke
				(width 0.1)
				(type default)
			)
			(layer "F.Fab")
		)
		(fp_line
			(start -0.67945 -0.305054)
			(end -0.12065 -0.305054)
			(stroke
				(width 0.1)
				(type default)
			)
			(layer "F.Fab")
		)
		(fp_line
			(start 0.67945 -0.3048)
			(end 0.67945 0.3048)
			(stroke
				(width 0.1)
				(type default)
			)
			(layer "F.Fab")
		)
		(fp_line
			(start 0.12065 -0.3048)
			(end 0.67945 -0.3048)
			(stroke
				(width 0.1)
				(type default)
			)
			(layer "F.Fab")
		)
		(fp_line
			(start 0.12065 -0.2794)
			(end 0.12065 -0.3048)
			(stroke
				(width 0.1)
				(type default)
			)
			(layer "F.Fab")
		)
		(fp_line
			(start -0.12065 -0.2794)
			(end 0.12065 -0.2794)
			(stroke
				(width 0.1)
				(type default)
			)
			(layer "F.Fab")
		)
		(fp_line
			(start 0.120396 0.2794)
			(end -0.12065 0.2794)
			(stroke
				(width 0.1)
				(type default)
			)
			(layer "F.Fab")
		)
		(fp_line
			(start -0.12065 0.2794)
			(end -0.12065 0.3048)
			(stroke
				(width 0.1)
				(type default)
			)
			(layer "F.Fab")
		)
		(fp_line
			(start 0.67945 0.3048)
			(end 0.120396 0.3048)
			(stroke
				(width 0.1)
				(type default)
			)
			(layer "F.Fab")
		)
		(fp_line
			(start 0.120396 0.3048)
			(end 0.120396 0.2794)
			(stroke
				(width 0.1)
				(type default)
			)
			(layer "F.Fab")
		)
		(fp_line
			(start -0.12065 0.3048)
			(end -0.67945 0.3048)
			(stroke
				(width 0.1)
				(type default)
			)
			(layer "F.Fab")
		)
		(fp_line
			(start -0.67945 0.3048)
			(end -0.67945 -0.305054)
			(stroke
				(width 0.1)
				(type default)
			)
			(layer "F.Fab")
		)
		(pad "1" smd circle
			(at -0.40005 0 90)
			(size 0 0)
			(layers "F.Cu" "F.Mask" "F.Paste")
			(net "PVPP_HBM_CPU1_REF")
		)
		(pad "2" smd circle
			(at 0.40005 0 90)
			(size 0 0)
			(layers "F.Cu" "F.Mask" "F.Paste")
			(net "GND")
		)
	)
	(footprint ""
		(layer "F.Cu")
		(at 357.720392 -400.354038)
		(property "Reference" "R2676"
			(at 0 0 0)
			(layer "F.SilkS")
			(hide yes)
			(effects
				(font
					(size 1.27 1.27)
				)
			)
		)
		(property "Value" ""
			(at 0 0 0)
			(layer "F.Fab")
			(effects
				(font
					(size 1.27 1.27)
				)
			)
		)
		(duplicate_pad_numbers_are_jumpers no)
		(fp_line
			(start -0.7874 -0.4064)
			(end 0.7874 -0.4064)
			(stroke
				(width 0.1524)
				(type default)
			)
			(layer "F.SilkS")
		)
		(fp_line
			(start -0.7874 0.4064)
			(end -0.7874 -0.4064)
			(stroke
				(width 0.1524)
				(type default)
			)
			(layer "F.SilkS")
		)
		(fp_line
			(start 0.7874 -0.4064)
			(end 0.7874 0.4064)
			(stroke
				(width 0.1524)
				(type default)
			)
			(layer "F.SilkS")
		)
		(fp_line
			(start 0.7874 0.4064)
			(end -0.7874 0.4064)
			(stroke
				(width 0.1524)
				(type default)
			)
			(layer "F.SilkS")
		)
		(fp_line
			(start -0.67945 -0.305054)
			(end -0.12065 -0.305054)
			(stroke
				(width 0.1)
				(type default)
			)
			(layer "F.Fab")
		)
		(fp_line
			(start -0.67945 0.3048)
			(end -0.67945 -0.305054)
			(stroke
				(width 0.1)
				(type default)
			)
			(layer "F.Fab")
		)
		(fp_line
			(start -0.12065 -0.305054)
			(end -0.12065 -0.2794)
			(stroke
				(width 0.1)
				(type default)
			)
			(layer "F.Fab")
		)
		(fp_line
			(start -0.12065 -0.2794)
			(end 0.12065 -0.2794)
			(stroke
				(width 0.1)
				(type default)
			)
			(layer "F.Fab")
		)
		(fp_line
			(start -0.12065 0.2794)
			(end -0.12065 0.3048)
			(stroke
				(width 0.1)
				(type default)
			)
			(layer "F.Fab")
		)
		(fp_line
			(start -0.12065 0.3048)
			(end -0.67945 0.3048)
			(stroke
				(width 0.1)
				(type default)
			)
			(layer "F.Fab")
		)
		(fp_line
			(start 0.120396 0.2794)
			(end -0.12065 0.2794)
			(stroke
				(width 0.1)
				(type default)
			)
			(layer "F.Fab")
		)
		(fp_line
			(start 0.120396 0.3048)
			(end 0.120396 0.2794)
			(stroke
				(width 0.1)
				(type default)
			)
			(layer "F.Fab")
		)
		(fp_line
			(start 0.12065 -0.3048)
			(end 0.67945 -0.3048)
			(stroke
				(width 0.1)
				(type default)
			)
			(layer "F.Fab")
		)
		(fp_line
			(start 0.12065 -0.2794)
			(end 0.12065 -0.3048)
			(stroke
				(width 0.1)
				(type default)
			)
			(layer "F.Fab")
		)
		(fp_line
			(start 0.67945 -0.3048)
			(end 0.67945 0.3048)
			(stroke
				(width 0.1)
				(type default)
			)
			(layer "F.Fab")
		)
		(fp_line
			(start 0.67945 0.3048)
			(end 0.120396 0.3048)
			(stroke
				(width 0.1)
				(type default)
			)
			(layer "F.Fab")
		)
		(pad "1" smd circle
			(at -0.40005 0)
			(size 0 0)
			(layers "F.Cu" "F.Mask" "F.Paste")
			(net "SMB_BMC_SWB_EN")
		)
		(pad "2" smd circle
			(at 0.40005 0)
			(size 0 0)
			(layers "F.Cu" "F.Mask" "F.Paste")
			(net "SMB_BMC_SWB_EN_R2")
		)
	)
	(footprint ""
		(layer "F.Cu")
		(at 425.846748 -353.312984 -90)
		(property "Reference" "PL2"
			(at -3.919474 -4.335272 0)
			(unlocked yes)
			(layer "F.SilkS")
			(effects
				(font
					(size 0.7874 0.5842)
					(thickness 0.1524)
				)
				(justify left)
			)
		)
		(property "Value" ""
			(at 0 0 270)
			(layer "F.Fab")
			(effects
				(font
					(size 1.27 1.27)
				)
			)
		)
		(duplicate_pad_numbers_are_jumpers no)
		(fp_line
			(start -4.99999 3.750056)
			(end -4.99999 2.2479)
			(stroke
				(width 0.1524)
				(type default)
			)
			(layer "F.SilkS")
		)
		(fp_line
			(start 0 3.750056)
			(end -4.99999 3.750056)
			(stroke
				(width 0.1524)
				(type default)
			)
			(layer "F.SilkS")
		)
		(fp_line
			(start 4.99999 3.750056)
			(end 0 3.750056)
			(stroke
				(width 0.1524)
				(type default)
			)
			(layer "F.SilkS")
		)
		(fp_line
			(start 4.99999 2.2352)
			(end 4.99999 3.750056)
			(stroke
				(width 0.1524)
				(type default)
			)
			(layer "F.SilkS")
		)
		(fp_line
			(start -4.99999 -2.2479)
			(end -4.99999 -3.750056)
			(stroke
				(width 0.1524)
				(type default)
			)
			(layer "F.SilkS")
		)
		(fp_line
			(start -4.99999 -3.750056)
			(end 4.99999 -3.750056)
			(stroke
				(width 0.1524)
				(type default)
			)
			(layer "F.SilkS")
		)
		(fp_line
			(start 4.99999 -3.750056)
			(end 4.99999 -2.2479)
			(stroke
				(width 0.1524)
				(type default)
			)
			(layer "F.SilkS")
		)
		(fp_line
			(start -4.99999 3.750056)
			(end -4.99999 -3.750056)
			(stroke
				(width 0.1)
				(type default)
			)
			(layer "F.Fab")
		)
		(fp_line
			(start 0 3.750056)
			(end -4.99999 3.750056)
			(stroke
				(width 0.1)
				(type default)
			)
			(layer "F.Fab")
		)
		(fp_line
			(start 4.99999 3.750056)
			(end 0 3.750056)
			(stroke
				(width 0.1)
				(type default)
			)
			(layer "F.Fab")
		)
		(fp_line
			(start -4.99999 -3.750056)
			(end 4.99999 -3.750056)
			(stroke
				(width 0.1)
				(type default)
			)
			(layer "F.Fab")
		)
		(fp_line
			(start 4.99999 -3.750056)
			(end 4.99999 3.750056)
			(stroke
				(width 0.1)
				(type default)
			)
			(layer "F.Fab")
		)
		(pad "1" smd rect
			(at -3.299968 0 270)
			(size 3.302 4.2164)
			(layers "F.Cu" "F.Mask" "F.Paste")
			(net "SW_PVCCFA_EHV_FIVRA_CPU0_SW3")
		)
		(pad "2" smd rect
			(at 3.299968 0 270)
			(size 3.302 4.2164)
			(layers "F.Cu" "F.Mask" "F.Paste")
			(net "PVCCFA_EHV_FIVRA_CPU0")
		)
	)
	(footprint ""
		(layer "F.Cu")
		(at 147.08378 -124.005848 180)
		(property "Reference" "R3153"
			(at 0 0 180)
			(layer "F.SilkS")
			(hide yes)
			(effects
				(font
					(size 1.27 1.27)
				)
			)
		)
		(property "Value" ""
			(at 0 0 180)
			(layer "F.Fab")
			(effects
				(font
					(size 1.27 1.27)
				)
			)
		)
		(duplicate_pad_numbers_are_jumpers no)
		(fp_line
			(start 0.7874 0.4064)
			(end -0.7874 0.4064)
			(stroke
				(width 0.1524)
				(type default)
			)
			(layer "F.SilkS")
		)
		(fp_line
			(start 0.7874 -0.4064)
			(end 0.7874 0.4064)
			(stroke
				(width 0.1524)
				(type default)
			)
			(layer "F.SilkS")
		)
		(fp_line
			(start -0.7874 0.4064)
			(end -0.7874 -0.4064)
			(stroke
				(width 0.1524)
				(type default)
			)
			(layer "F.SilkS")
		)
		(fp_line
			(start -0.7874 -0.4064)
			(end 0.7874 -0.4064)
			(stroke
				(width 0.1524)
				(type default)
			)
			(layer "F.SilkS")
		)
		(fp_line
			(start 0.67945 0.3048)
			(end 0.120396 0.3048)
			(stroke
				(width 0.1)
				(type default)
			)
			(layer "F.Fab")
		)
		(fp_line
			(start 0.67945 -0.3048)
			(end 0.67945 0.3048)
			(stroke
				(width 0.1)
				(type default)
			)
			(layer "F.Fab")
		)
		(fp_line
			(start 0.12065 -0.2794)
			(end 0.12065 -0.3048)
			(stroke
				(width 0.1)
				(type default)
			)
			(layer "F.Fab")
		)
		(fp_line
			(start 0.12065 -0.3048)
			(end 0.67945 -0.3048)
			(stroke
				(width 0.1)
				(type default)
			)
			(layer "F.Fab")
		)
		(fp_line
			(start 0.120396 0.3048)
			(end 0.120396 0.2794)
			(stroke
				(width 0.1)
				(type default)
			)
			(layer "F.Fab")
		)
		(fp_line
			(start 0.120396 0.2794)
			(end -0.12065 0.2794)
			(stroke
				(width 0.1)
				(type default)
			)
			(layer "F.Fab")
		)
		(fp_line
			(start -0.12065 0.3048)
			(end -0.67945 0.3048)
			(stroke
				(width 0.1)
				(type default)
			)
			(layer "F.Fab")
		)
		(fp_line
			(start -0.12065 0.2794)
			(end -0.12065 0.3048)
			(stroke
				(width 0.1)
				(type default)
			)
			(layer "F.Fab")
		)
		(fp_line
			(start -0.12065 -0.2794)
			(end 0.12065 -0.2794)
			(stroke
				(width 0.1)
				(type default)
			)
			(layer "F.Fab")
		)
		(fp_line
			(start -0.12065 -0.305054)
			(end -0.12065 -0.2794)
			(stroke
				(width 0.1)
				(type default)
			)
			(layer "F.Fab")
		)
		(fp_line
			(start -0.67945 0.3048)
			(end -0.67945 -0.305054)
			(stroke
				(width 0.1)
				(type default)
			)
			(layer "F.Fab")
		)
		(fp_line
			(start -0.67945 -0.305054)
			(end -0.12065 -0.305054)
			(stroke
				(width 0.1)
				(type default)
			)
			(layer "F.Fab")
		)
		(pad "1" smd circle
			(at -0.40005 0 180)
			(size 0 0)
			(layers "F.Cu" "F.Mask" "F.Paste")
			(net "P3V3_AUX")
		)
		(pad "2" smd circle
			(at 0.40005 0 180)
			(size 0 0)
			(layers "F.Cu" "F.Mask" "F.Paste")
			(net "PD_SMB_OCP2_HP_ADD0")
		)
	)
	(footprint ""
		(layer "F.Cu")
		(at 63.877698 -26.99004 -90)
		(property "Reference" "PR3854"
			(at 0 0 270)
			(layer "F.SilkS")
			(hide yes)
			(effects
				(font
					(size 1.27 1.27)
				)
			)
		)
		(property "Value" ""
			(at 0 0 270)
			(layer "F.Fab")
			(effects
				(font
					(size 1.27 1.27)
				)
			)
		)
		(duplicate_pad_numbers_are_jumpers no)
		(fp_line
			(start -0.7874 0.4064)
			(end -0.7874 -0.4064)
			(stroke
				(width 0.1524)
				(type default)
			)
			(layer "F.SilkS")
		)
		(fp_line
			(start 0.7874 0.4064)
			(end -0.7874 0.4064)
			(stroke
				(width 0.1524)
				(type default)
			)
			(layer "F.SilkS")
		)
		(fp_line
			(start -0.7874 -0.4064)
			(end 0.7874 -0.4064)
			(stroke
				(width 0.1524)
				(type default)
			)
			(layer "F.SilkS")
		)
		(fp_line
			(start 0.7874 -0.4064)
			(end 0.7874 0.4064)
			(stroke
				(width 0.1524)
				(type default)
			)
			(layer "F.SilkS")
		)
		(fp_line
			(start -0.67945 0.3048)
			(end -0.67945 -0.305054)
			(stroke
				(width 0.1)
				(type default)
			)
			(layer "F.Fab")
		)
		(fp_line
			(start -0.12065 0.3048)
			(end -0.67945 0.3048)
			(stroke
				(width 0.1)
				(type default)
			)
			(layer "F.Fab")
		)
		(fp_line
			(start 0.120396 0.3048)
			(end 0.120396 0.2794)
			(stroke
				(width 0.1)
				(type default)
			)
			(layer "F.Fab")
		)
		(fp_line
			(start 0.67945 0.3048)
			(end 0.120396 0.3048)
			(stroke
				(width 0.1)
				(type default)
			)
			(layer "F.Fab")
		)
		(fp_line
			(start -0.12065 0.2794)
			(end -0.12065 0.3048)
			(stroke
				(width 0.1)
				(type default)
			)
			(layer "F.Fab")
		)
		(fp_line
			(start 0.120396 0.2794)
			(end -0.12065 0.2794)
			(stroke
				(width 0.1)
				(type default)
			)
			(layer "F.Fab")
		)
		(fp_line
			(start -0.12065 -0.2794)
			(end 0.12065 -0.2794)
			(stroke
				(width 0.1)
				(type default)
			)
			(layer "F.Fab")
		)
		(fp_line
			(start 0.12065 -0.2794)
			(end 0.12065 -0.3048)
			(stroke
				(width 0.1)
				(type default)
			)
			(layer "F.Fab")
		)
		(fp_line
			(start 0.12065 -0.3048)
			(end 0.67945 -0.3048)
			(stroke
				(width 0.1)
				(type default)
			)
			(layer "F.Fab")
		)
		(fp_line
			(start 0.67945 -0.3048)
			(end 0.67945 0.3048)
			(stroke
				(width 0.1)
				(type default)
			)
			(layer "F.Fab")
		)
		(fp_line
			(start -0.67945 -0.305054)
			(end -0.12065 -0.305054)
			(stroke
				(width 0.1)
				(type default)
			)
			(layer "F.Fab")
		)
		(fp_line
			(start -0.12065 -0.305054)
			(end -0.12065 -0.2794)
			(stroke
				(width 0.1)
				(type default)
			)
			(layer "F.Fab")
		)
		(pad "1" smd circle
			(at -0.40005 0 270)
			(size 0 0)
			(layers "F.Cu" "F.Mask" "F.Paste")
			(net "P12V_OCP_OV_FB_2")
		)
		(pad "2" smd circle
			(at 0.40005 0 270)
			(size 0 0)
			(layers "F.Cu" "F.Mask" "F.Paste")
			(net "GND")
		)
	)
)
